#ISCELL
  pure_quanta quanta_title_block_c *
  *
#CELL
  pure_quanta q_cap *
  page71_i1
#ISCELL
  pure_quanta_power universal_power *
  page71_i10
#CELL
  pure_quanta q_cap *
  page71_i11
#CELL
  pure_quanta q_cap *
  page71_i12
#CELL
  pure_quanta q_cap *
  page71_i13
#CELL
  pure_quanta q_cap *
  page71_i14
#CELL
  pure_quanta q_cap *
  page71_i15
#CELL
  pure_quanta q_cap *
  page71_i16
#ISCELL
  pure_quanta_power universal_gnd *
  page71_i17
#CELL
  pure_quanta q_cap *
  page71_i18
#CELL
  pure_quanta q_cap *
  page71_i19
#ISCELL
  pure_quanta_power universal_power *
  page71_i2
#CELL
  pure_quanta q_cap *
  page71_i20
#CELL
  pure_quanta q_cap *
  page71_i21
#ISCELL
  pure_quanta_power universal_gnd *
  page71_i22
#CELL
  pure_quanta q_cap *
  page71_i23
#CELL
  pure_quanta q_cap *
  page71_i24
#CELL
  pure_quanta q_cap *
  page71_i25
#CELL
  pure_quanta q_cap *
  page71_i26
#ISCELL
  pure_quanta_power universal_gnd *
  page71_i27
#CELL
  pure_quanta q_cap *
  page71_i28
#ISCELL
  pure_quanta_power universal_gnd *
  page71_i29
#CELL
  pure_quanta q_cap *
  page71_i3
#CELL
  pure_quanta q_cap *
  page71_i30
#CELL
  pure_quanta q_cap *
  page71_i31
#CELL
  pure_quanta q_cap *
  page71_i32
#CELL
  pure_quanta q_cap *
  page71_i33
#CELL
  pure_quanta q_cap *
  page71_i34
#CELL
  pure_quanta q_cap *
  page71_i35
#CELL
  pure_quanta q_cap *
  page71_i36
#CELL
  pure_quanta q_cap *
  page71_i37
#CELL
  pure_quanta q_cap *
  page71_i38
#CELL
  pure_quanta q_cap *
  page71_i39
#ISCELL
  pure_quanta_power universal_power *
  page71_i4
#CELL
  pure_quanta q_cap *
  page71_i40
#CELL
  pure_quanta q_cap *
  page71_i41
#CELL
  pure_quanta q_cap *
  page71_i42
#CELL
  pure_quanta q_cap *
  page71_i43
#CELL
  pure_quanta q_cap *
  page71_i44
#CELL
  pure_quanta q_cap *
  page71_i45
#ISCELL
  pure_quanta_power universal_gnd *
  page71_i46
#CELL
  pure_quanta q_cap *
  page71_i47
#ISCELL
  pure_quanta_power universal_power *
  page71_i48
#CELL
  pure_quanta q_cap *
  page71_i49
#CELL
  pure_quanta q_cap *
  page71_i5
#CELL
  pure_quanta q_cap *
  page71_i50
#ISCELL
  pure_quanta_power universal_gnd *
  page71_i51
#CELL
  pure_quanta q_cap *
  page71_i52
#CELL
  pure_quanta q_cap *
  page71_i53
#CELL
  pure_quanta q_cap *
  page71_i54
#ISCELL
  pure_quanta_power universal_power *
  page71_i55
#CELL
  pure_quanta q_cap *
  page71_i56
#CELL
  pure_quanta q_cap *
  page71_i57
#CELL
  pure_quanta q_cap *
  page71_i58
#CELL
  pure_quanta q_cap *
  page71_i59
#ISCELL
  pure_quanta_power universal_power *
  page71_i6
#ISCELL
  pure_quanta_power universal_gnd *
  page71_i60
#CELL
  pure_quanta q_cap *
  page71_i61
#CELL
  pure_quanta q_cap *
  page71_i62
#CELL
  pure_quanta q_cap *
  page71_i7
#ISCELL
  pure_quanta_power universal_power *
  page71_i8
#CELL
  pure_quanta q_cap *
  page71_i9
